# S9S_MB_2U (Grand Teton) — schematic netlist excerpt (pin names and nets, part order shuffled) for the footprints in the layout excerpt that follows; sources: Cadence DE-HDL packaged netlist, KiCad conversion of 03242023_DA0F0TMBIJ0_F0T_Motherboard_J_brd_V01_OCP.brd

C15  Q_CAP  10UF 16V 10% X6S  pkg C0805  page 86 : A = P12V_S3_AUX_CPU0_NVDIMM ; B = GND
C1204  Q_CAP  2.2UF 10V 10% X6S  pkg C0402  page 189 : A = P1V05_PCH_AUX ; B = GND
PC2240  Q_CAP  10UF 16V 10% X6S  pkg C0805  page 242 : A = P12V_SCM_R ; B = GND

(kicad_pcb
	(version 20260206)
	(generator "pcbnew")
	(generator_version "10.0")
	(general
		(thickness 1.6)
		(legacy_teardrops no)
	)
	(paper "A4")
	(title_block
		(title "03242023_DA0F0TMBIJ0_F0T_Motherboard_J_brd_V01_OCP.brd")
		(comment 1 "Grand Teton / footprints 5299-5301 of 6105")
	)
	(layers
		(0 "F.Cu" signal "TOP")
		(4 "In1.Cu" signal "GND")
		(6 "In2.Cu" signal "IN1")
		(8 "In3.Cu" signal "GND1")
		(10 "In4.Cu" signal "IN2")
		(12 "In5.Cu" signal "GND2")
		(14 "In6.Cu" signal "IN3")
		(16 "In7.Cu" signal "GND3")
		(18 "In8.Cu" signal "VCC")
		(20 "In9.Cu" signal "VCC1")
		(22 "In10.Cu" signal "GND4")
		(24 "In11.Cu" signal "IN4")
		(26 "In12.Cu" signal "GND5")
		(28 "In13.Cu" signal "IN5")
		(30 "In14.Cu" signal "GND6")
		(32 "In15.Cu" signal "IN6")
		(34 "In16.Cu" signal "GND7")
		(2 "B.Cu" signal "BOTTOM")
		(9 "F.Adhes" user "F.Adhesive")
		(11 "B.Adhes" user "B.Adhesive")
		(13 "F.Paste" user "Package Geometry/Pastemask Top")
		(15 "B.Paste" user "Package Geometry/Pastemask Bottom")
		(5 "F.SilkS" user "Ref Des/Silkscreen Top")
		(7 "B.SilkS" user "Ref Des/Silkscreen Bottom")
		(1 "F.Mask" user "Board Geometry/Soldermask Top")
		(3 "B.Mask" user "Board Geometry/Soldermask Bottom")
		(17 "Dwgs.User" user "User.Drawings")
		(19 "Cmts.User" user "User.Comments")
		(21 "Eco1.User" user "User.Eco1")
		(23 "Eco2.User" user "User.Eco2")
		(25 "Edge.Cuts" user "Board Geometry/Outline")
		(27 "Margin" user)
		(31 "F.CrtYd" user "Package Geometry/Place Bound Top")
		(29 "B.CrtYd" user "Package Geometry/Place Bound Bottom")
		(35 "F.Fab" user "Ref Des/Assembly Top")
		(33 "B.Fab" user "Ref Des/Assembly Bottom")
	)
	(footprint ""
		(layer "B.Cu")
		(at 336.1563 -42.537888)
		(property "Reference" "C1204"
			(at 0 0 0)
			(layer "B.SilkS")
			(hide yes)
			(effects
				(font
					(size 1.27 1.27)
				)
				(justify mirror)
			)
		)
		(property "Value" ""
			(at 0 0 0)
			(layer "B.Fab")
			(effects
				(font
					(size 1.27 1.27)
				)
				(justify mirror)
			)
		)
		(duplicate_pad_numbers_are_jumpers no)
		(fp_line
			(start -0.7874 -0.4064)
			(end -0.7874 0.4064)
			(stroke
				(width 0.1524)
				(type default)
			)
			(layer "B.SilkS")
		)
		(fp_line
			(start -0.7874 0.4064)
			(end 0.7874 0.4064)
			(stroke
				(width 0.1524)
				(type default)
			)
			(layer "B.SilkS")
		)
		(fp_line
			(start 0.7874 -0.4064)
			(end -0.7874 -0.4064)
			(stroke
				(width 0.1524)
				(type default)
			)
			(layer "B.SilkS")
		)
		(fp_line
			(start 0.7874 0.4064)
			(end 0.7874 -0.4064)
			(stroke
				(width 0.1524)
				(type default)
			)
			(layer "B.SilkS")
		)
		(fp_line
			(start -0.67945 -0.3048)
			(end -0.67945 0.3048)
			(stroke
				(width 0.1)
				(type default)
			)
			(layer "B.Fab")
		)
		(fp_line
			(start -0.67945 0.3048)
			(end -0.120396 0.3048)
			(stroke
				(width 0.1)
				(type default)
			)
			(layer "B.Fab")
		)
		(fp_line
			(start -0.12065 -0.3048)
			(end -0.67945 -0.3048)
			(stroke
				(width 0.1)
				(type default)
			)
			(layer "B.Fab")
		)
		(fp_line
			(start -0.12065 -0.2794)
			(end -0.12065 -0.3048)
			(stroke
				(width 0.1)
				(type default)
			)
			(layer "B.Fab")
		)
		(fp_line
			(start -0.120396 0.2794)
			(end 0.12065 0.2794)
			(stroke
				(width 0.1)
				(type default)
			)
			(layer "B.Fab")
		)
		(fp_line
			(start -0.120396 0.3048)
			(end -0.120396 0.2794)
			(stroke
				(width 0.1)
				(type default)
			)
			(layer "B.Fab")
		)
		(fp_line
			(start 0.12065 -0.305054)
			(end 0.12065 -0.2794)
			(stroke
				(width 0.1)
				(type default)
			)
			(layer "B.Fab")
		)
		(fp_line
			(start 0.12065 -0.2794)
			(end -0.12065 -0.2794)
			(stroke
				(width 0.1)
				(type default)
			)
			(layer "B.Fab")
		)
		(fp_line
			(start 0.12065 0.2794)
			(end 0.12065 0.3048)
			(stroke
				(width 0.1)
				(type default)
			)
			(layer "B.Fab")
		)
		(fp_line
			(start 0.12065 0.3048)
			(end 0.67945 0.3048)
			(stroke
				(width 0.1)
				(type default)
			)
			(layer "B.Fab")
		)
		(fp_line
			(start 0.67945 -0.305054)
			(end 0.12065 -0.305054)
			(stroke
				(width 0.1)
				(type default)
			)
			(layer "B.Fab")
		)
		(fp_line
			(start 0.67945 0.3048)
			(end 0.67945 -0.305054)
			(stroke
				(width 0.1)
				(type default)
			)
			(layer "B.Fab")
		)
		(pad "1" smd circle
			(at 0.40005 0 180)
			(size 0 0)
			(layers "B.Cu" "B.Mask" "B.Paste")
			(net "P1V05_PCH_AUX")
		)
		(pad "2" smd circle
			(at -0.40005 0 180)
			(size 0 0)
			(layers "B.Cu" "B.Mask" "B.Paste")
			(net "GND")
		)
	)
	(footprint ""
		(layer "B.Cu")
		(at 174.98568 -24.653748)
		(property "Reference" "PC2240"
			(at 0 0 0)
			(layer "B.SilkS")
			(hide yes)
			(effects
				(font
					(size 1.27 1.27)
				)
				(justify mirror)
			)
		)
		(property "Value" ""
			(at 0 0 0)
			(layer "B.Fab")
			(effects
				(font
					(size 1.27 1.27)
				)
				(justify mirror)
			)
		)
		(duplicate_pad_numbers_are_jumpers no)
		(fp_line
			(start -1.524 -0.762)
			(end -1.524 0.762)
			(stroke
				(width 0.1524)
				(type default)
			)
			(layer "B.SilkS")
		)
		(fp_line
			(start -1.524 0.762)
			(end 1.524 0.762)
			(stroke
				(width 0.1524)
				(type default)
			)
			(layer "B.SilkS")
		)
		(fp_line
			(start 1.524 -0.762)
			(end -1.524 -0.762)
			(stroke
				(width 0.1524)
				(type default)
			)
			(layer "B.SilkS")
		)
		(fp_line
			(start 1.524 0.762)
			(end 1.524 -0.762)
			(stroke
				(width 0.1524)
				(type default)
			)
			(layer "B.SilkS")
		)
		(fp_line
			(start -1.1049 -0.724916)
			(end 1.1049 -0.724916)
			(stroke
				(width 0.1)
				(type default)
			)
			(layer "B.Fab")
		)
		(fp_line
			(start -1.1049 0.724916)
			(end -1.1049 -0.724916)
			(stroke
				(width 0.1)
				(type default)
			)
			(layer "B.Fab")
		)
		(fp_line
			(start 1.1049 -0.724916)
			(end 1.1049 0.724916)
			(stroke
				(width 0.1)
				(type default)
			)
			(layer "B.Fab")
		)
		(fp_line
			(start 1.1049 0.724916)
			(end -1.1049 0.724916)
			(stroke
				(width 0.1)
				(type default)
			)
			(layer "B.Fab")
		)
		(pad "1" smd rect
			(at 0.889 0)
			(size 1.016 1.27)
			(layers "B.Cu" "B.Mask" "B.Paste")
			(net "P12V_SCM_R")
		)
		(pad "2" smd rect
			(at -0.889 0)
			(size 1.016 1.27)
			(layers "B.Cu" "B.Mask" "B.Paste")
			(net "GND")
		)
	)
	(footprint ""
		(layer "B.Cu")
		(at 275.244814 -321.549776 -90)
		(property "Reference" "C15"
			(at 0 0 90)
			(layer "B.SilkS")
			(hide yes)
			(effects
				(font
					(size 1.27 1.27)
				)
				(justify mirror)
			)
		)
		(property "Value" ""
			(at 0 0 90)
			(layer "B.Fab")
			(effects
				(font
					(size 1.27 1.27)
				)
				(justify mirror)
			)
		)
		(duplicate_pad_numbers_are_jumpers no)
		(fp_line
			(start -1.524 0.762)
			(end 1.524 0.762)
			(stroke
				(width 0.1524)
				(type default)
			)
			(layer "B.SilkS")
		)
		(fp_line
			(start 1.524 0.762)
			(end 1.524 -0.762)
			(stroke
				(width 0.1524)
				(type default)
			)
			(layer "B.SilkS")
		)
		(fp_line
			(start -1.524 -0.762)
			(end -1.524 0.762)
			(stroke
				(width 0.1524)
				(type default)
			)
			(layer "B.SilkS")
		)
		(fp_line
			(start 1.524 -0.762)
			(end -1.524 -0.762)
			(stroke
				(width 0.1524)
				(type default)
			)
			(layer "B.SilkS")
		)
		(fp_line
			(start -1.1049 0.724916)
			(end -1.1049 -0.724916)
			(stroke
				(width 0.1)
				(type default)
			)
			(layer "B.Fab")
		)
		(fp_line
			(start 1.1049 0.724916)
			(end -1.1049 0.724916)
			(stroke
				(width 0.1)
				(type default)
			)
			(layer "B.Fab")
		)
		(fp_line
			(start -1.1049 -0.724916)
			(end 1.1049 -0.724916)
			(stroke
				(width 0.1)
				(type default)
			)
			(layer "B.Fab")
		)
		(fp_line
			(start 1.1049 -0.724916)
			(end 1.1049 0.724916)
			(stroke
				(width 0.1)
				(type default)
			)
			(layer "B.Fab")
		)
		(pad "1" smd rect
			(at 0.889 0 270)
			(size 1.016 1.27)
			(layers "B.Cu" "B.Mask" "B.Paste")
			(net "P12V_S3_AUX_CPU0_NVDIMM")
		)
		(pad "2" smd rect
			(at -0.889 0 270)
			(size 1.016 1.27)
			(layers "B.Cu" "B.Mask" "B.Paste")
			(net "GND")
		)
	)
)
